(kicad_sch (version 20230121) (generator eeschema)

  (paper "A3")

  (title_block
    (title "HDMI-MIPI Bridge")
    (date "2024-04-24")
    (rev "1.3.2")
  )

  (symbol (lib_id "antmicroMechanicalParts:antmicro_logo") (at 74.93 274.32 0) (unit 1)
    (in_bom no) (on_board yes) (dnp no) (fields_autoplaced)
    (property "Reference" "N1" (at 81.28 272.3362 0)
      (effects (font (size 1.27 1.27) (thickness 0.15)) (justify left))
    )
    (property "Value" "antmicro_logo" (at 81.28 274.8762 0)
      (effects (font (size 1.27 1.27) (thickness 0.15)) (justify left))
    )
    (property "Footprint" "antmicro-footprints:antmicro-logo_scaled_20mm_mask" (at 90.17 284.48 0)
      (effects (font (size 1.27 1.27) (thickness 0.15)) (justify left bottom) hide)
    )
    (property "Datasheet" "" (at 90.17 287.02 0)
      (effects (font (size 1.27 1.27) (thickness 0.15)) (justify left bottom) hide)
    )
    (property "MPN" "" (at 74.93 274.32 0)
      (effects (font (size 1.27 1.27)))
    )
    (property "Manufacturer" "" (at 90.17 294.64 0)
      (effects (font (size 1.27 1.27) (thickness 0.15)) (justify left bottom) hide)
    )
    (property "Author" "Antmicro" (at 90.17 289.56 0)
      (effects (font (size 1.27 1.27) (thickness 0.15)) (justify left bottom) hide)
    )
    (property "License" "Apache-2.0" (at 90.17 292.1 0)
      (effects (font (size 1.27 1.27) (thickness 0.15)) (justify left bottom) hide)
    )
    (property "Public" "False" (at 90.17 294.64 0)
      (effects (font (size 1.27 1.27)) (justify left bottom) hide)
    )
    (instances
      (project "antmicro-hdmi-mipi-bridge-hw"
        (path ""
          (reference "N1") (unit 1)
        )
      )
    )
  )

  (symbol (lib_id "antmicroMechanicalParts:oshw_logo") (at 95.25 274.32 0) (unit 1)
    (in_bom no) (on_board yes) (dnp no) (fields_autoplaced)
    (property "Reference" "N2" (at 101.6 272.3362 0)
      (effects (font (size 1.27 1.27) (thickness 0.15)) (justify left))
    )
    (property "Value" "oshw_logo" (at 101.6 274.8762 0)
      (effects (font (size 1.27 1.27) (thickness 0.15)) (justify left))
    )
    (property "Footprint" "antmicro-footprints:OSHW-Logo_7.5x8mm_Mask" (at 110.49 284.48 0)
      (effects (font (size 1.27 1.27) (thickness 0.15)) (justify left bottom) hide)
    )
    (property "Datasheet" "" (at 110.49 287.02 0)
      (effects (font (size 1.27 1.27) (thickness 0.15)) (justify left bottom) hide)
    )
    (property "Author" "Antmicro" (at 110.49 289.56 0)
      (effects (font (size 1.27 1.27) (thickness 0.15)) (justify left bottom) hide)
    )
    (property "License" "Apache-2.0" (at 110.49 292.1 0)
      (effects (font (size 1.27 1.27) (thickness 0.15)) (justify left bottom) hide)
    )
    (property "MPN" "" (at 95.25 274.32 0)
      (effects (font (size 1.27 1.27)))
    )
    (property "Manufacturer" "" (at 110.49 294.64 0)
      (effects (font (size 1.27 1.27) (thickness 0.15)) (justify left bottom) hide)
    )
    (property "Public" "False" (at 110.49 294.64 0)
      (effects (font (size 1.27 1.27)) (justify left bottom) hide)
    )
    (instances
      (project "antmicro-hdmi-mipi-bridge-hw"
        (path ""
          (reference "N2") (unit 1)
        )
      )
    )
  )

  (sheet (at 101.6 190.5) (size 63.5 50.8) (fields_autoplaced)
    (stroke (width 0.1524) (type solid))
    (fill (color 0 0 0 0.0000))
    (property "Sheetname" "Channel 1" (at 101.6 188.4234 0)
      (effects (font (size 4 4)) (justify left bottom))
    )
    (property "Sheetfile" "channel1.kicad_sch" (at 101.6 241.8846 0)
      (effects (font (size 1.27 1.27)) (justify left top))
    )
    (instances
      (project "antmicro-hdmi-mipi-bridge-hw"
        (path "" (page "2"))
      )
    )
  )

  (sheet (at 254 190.5) (size 63.5 50.8) (fields_autoplaced)
    (stroke (width 0.1524) (type solid))
    (fill (color 0 0 0 0.0000))
    (property "Sheetname" "CSI" (at 254 188.4234 0)
      (effects (font (size 4 4)) (justify left bottom))
    )
    (property "Sheetfile" "csi.kicad_sch" (at 254 241.8846 0)
      (effects (font (size 1.27 1.27)) (justify left top))
    )
    (instances
      (project "antmicro-hdmi-mipi-bridge-hw"
        (path "" (page "4"))
      )
    )
  )

  (sheet (at 177.8 190.5) (size 63.5 50.8) (fields_autoplaced)
    (stroke (width 0.1524) (type solid))
    (fill (color 0 0 0 0.0000))
    (property "Sheetname" "Channel 2" (at 177.8 188.4234 0)
      (effects (font (size 4 4)) (justify left bottom))
    )
    (property "Sheetfile" "channel2.kicad_sch" (at 177.8 241.8846 0)
      (effects (font (size 1.27 1.27)) (justify left top))
    )
    (instances
      (project "antmicro-hdmi-mipi-bridge-hw"
        (path "" (page "3"))
      )
    )
  )

  (sheet_instances
    (path "/" (page "1"))
  )
)
